# BASEBOARD_FAB2 (Tioga Pass) — schematic netlist excerpt (pin names and nets, part order shuffled) for the footprints in the layout excerpt that follows; sources: Cadence DE-HDL packaged netlist, KiCad conversion of Wiwynn_Tioga_Pass_MB.brd

C1L17  CAP_A  0.1UF 16V 10% X7R  pkg 0402V  page 175 : A = P3V3_STBY ; B = GND
C8A11  CAP  1000PF 50V 10% X7R  pkg 0402LF  page 237 : A = PWRGD_P1V8_PCH_STBY_R ; B = GND
R9F60  RES  0.0 5% EMPTY  pkg 0402  page 145 : A = CLK_25M_BMC ; B = CLK_24M_25M_BMC_CLKIN

(kicad_pcb
	(version 20260206)
	(generator "pcbnew")
	(generator_version "10.0")
	(general
		(thickness 1.6)
		(legacy_teardrops no)
	)
	(paper "A4")
	(title_block
		(title "Wiwynn_Tioga_Pass_MB.brd")
		(comment 1 "Tioga Pass / footprints 1214-1216 of 4770")
	)
	(layers
		(0 "F.Cu" signal "TOP")
		(4 "In1.Cu" signal "L2GND")
		(6 "In2.Cu" signal "L3")
		(8 "In3.Cu" signal "L4GND")
		(10 "In4.Cu" signal "L5")
		(12 "In5.Cu" signal "L6GND")
		(14 "In6.Cu" signal "L7VCC")
		(16 "In7.Cu" signal "L8VCC")
		(18 "In8.Cu" signal "L9GND")
		(20 "In9.Cu" signal "L10")
		(22 "In10.Cu" signal "L11GND")
		(24 "In11.Cu" signal "L12")
		(26 "In12.Cu" signal "L13GND")
		(2 "B.Cu" signal "BOTTOM")
		(9 "F.Adhes" user "F.Adhesive")
		(11 "B.Adhes" user "B.Adhesive")
		(13 "F.Paste" user "Package Geometry/Pastemask Top")
		(15 "B.Paste" user "Package Geometry/Pastemask Bottom")
		(5 "F.SilkS" user "Ref Des/Silkscreen Top")
		(7 "B.SilkS" user "Ref Des/Silkscreen Bottom")
		(1 "F.Mask" user "Board Geometry/Soldermask Top")
		(3 "B.Mask" user "Board Geometry/Soldermask Bottom")
		(17 "Dwgs.User" user "User.Drawings")
		(19 "Cmts.User" user "User.Comments")
		(21 "Eco1.User" user "User.Eco1")
		(23 "Eco2.User" user "User.Eco2")
		(25 "Edge.Cuts" user "Board Geometry/Outline")
		(27 "Margin" user)
		(31 "F.CrtYd" user "Package Geometry/Place Bound Top")
		(29 "B.CrtYd" user "Package Geometry/Place Bound Bottom")
		(35 "F.Fab" user "Ref Des/Assembly Top")
		(33 "B.Fab" user "Ref Des/Assembly Bottom")
	)
	(footprint ""
		(layer "F.Cu")
		(at 405.283416 -148.436584 90)
		(property "Reference" "C8A11"
			(at 0 0 90)
			(layer "F.SilkS")
			(hide yes)
			(effects
				(font
					(size 1.27 1.27)
				)
			)
		)
		(property "Value" ""
			(at 0 0 90)
			(layer "F.Fab")
			(effects
				(font
					(size 1.27 1.27)
				)
			)
		)
		(duplicate_pad_numbers_are_jumpers no)
		(fp_poly
			(pts
				(xy 0.3048 -0.1016) (xy 0.3048 0.9906) (xy -0.3048 0.9906) (xy -0.3048 -0.1016)
			)
			(stroke
				(width 0)
				(type default)
			)
			(fill no)
			(layer "F.CrtYd")
		)
		(fp_line
			(start 0.3048 -0.1016)
			(end -0.3048 -0.1016)
			(stroke
				(width 0.1)
				(type default)
			)
			(layer "F.Fab")
		)
		(fp_line
			(start -0.3048 -0.1016)
			(end -0.3048 0.9906)
			(stroke
				(width 0.1)
				(type default)
			)
			(layer "F.Fab")
		)
		(fp_line
			(start 0.3048 0.9906)
			(end 0.3048 -0.1016)
			(stroke
				(width 0.1)
				(type default)
			)
			(layer "F.Fab")
		)
		(fp_line
			(start -0.3048 0.9906)
			(end 0.3048 0.9906)
			(stroke
				(width 0.1)
				(type default)
			)
			(layer "F.Fab")
		)
		(pad "1" smd rect
			(at 0 0 90)
			(size 0.508 0.508)
			(layers "F.Cu" "F.Mask" "F.Paste")
			(net "PWRGD_P1V8_PCH_STBY_R")
		)
		(pad "2" smd rect
			(at 0 0.889 90)
			(size 0.508 0.508)
			(layers "F.Cu" "F.Mask" "F.Paste")
			(net "GND")
		)
		(zone
			(layer "F.Cu")
			(hatch none 0.5)
			(connect_pads
				(clearance 0)
			)
			(min_thickness 0.25)
			(keepout
				(tracks allowed)
				(vias not_allowed)
				(pads allowed)
				(copperpour not_allowed)
				(footprints allowed)
			)
			(placement
				(enabled no)
				(sheetname "")
			)
			(fill
				(thermal_gap 0.5)
				(thermal_bridge_width 0.5)
				(island_removal_mode 0)
			)
			(polygon
				(pts
					(xy 405.537416 -148.182584) (xy 405.537416 -148.690584) (xy 405.918416 -148.690584) (xy 405.918416 -148.182584)
				)
			)
		)
		(zone
			(layer "F.Cu")
			(hatch none 0.5)
			(connect_pads
				(clearance 0)
			)
			(min_thickness 0.25)
			(keepout
				(tracks not_allowed)
				(vias allowed)
				(pads allowed)
				(copperpour not_allowed)
				(footprints allowed)
			)
			(placement
				(enabled no)
				(sheetname "")
			)
			(fill
				(thermal_gap 0.5)
				(thermal_bridge_width 0.5)
				(island_removal_mode 0)
			)
			(polygon
				(pts
					(xy 405.918416 -148.182584) (xy 405.918416 -148.690584) (xy 405.537416 -148.690584) (xy 405.537416 -148.182584)
				)
			)
		)
	)
	(footprint ""
		(layer "F.Cu")
		(at 429.220122 -45.054774 90)
		(property "Reference" "R9F60"
			(at 0 0 90)
			(layer "F.SilkS")
			(hide yes)
			(effects
				(font
					(size 1.27 1.27)
				)
			)
		)
		(property "Value" ""
			(at 0 0 90)
			(layer "F.Fab")
			(effects
				(font
					(size 1.27 1.27)
				)
			)
		)
		(duplicate_pad_numbers_are_jumpers no)
		(fp_poly
			(pts
				(xy -0.2794 -0.1016) (xy 0.2794 -0.1016) (xy 0.2794 0.9906) (xy -0.2794 0.9906)
			)
			(stroke
				(width 0)
				(type default)
			)
			(fill no)
			(layer "F.CrtYd")
		)
		(fp_line
			(start 0.2794 -0.1016)
			(end -0.2794 -0.1016)
			(stroke
				(width 0.1)
				(type default)
			)
			(layer "F.Fab")
		)
		(fp_line
			(start -0.2794 -0.1016)
			(end -0.2794 0.9906)
			(stroke
				(width 0.1)
				(type default)
			)
			(layer "F.Fab")
		)
		(fp_line
			(start 0.2794 0.9906)
			(end 0.2794 -0.1016)
			(stroke
				(width 0.1)
				(type default)
			)
			(layer "F.Fab")
		)
		(fp_line
			(start -0.2794 0.9906)
			(end 0.2794 0.9906)
			(stroke
				(width 0.1)
				(type default)
			)
			(layer "F.Fab")
		)
		(pad "1" smd rect
			(at 0 0 90)
			(size 0.508 0.508)
			(layers "F.Cu" "F.Mask" "F.Paste")
			(net "CLK_25M_BMC")
		)
		(pad "2" smd rect
			(at 0 0.889 90)
			(size 0.508 0.508)
			(layers "F.Cu" "F.Mask" "F.Paste")
			(net "CLK_24M_25M_BMC_CLKIN")
		)
		(zone
			(layer "F.Cu")
			(hatch none 0.5)
			(connect_pads
				(clearance 0)
			)
			(min_thickness 0.25)
			(keepout
				(tracks allowed)
				(vias not_allowed)
				(pads allowed)
				(copperpour not_allowed)
				(footprints allowed)
			)
			(placement
				(enabled no)
				(sheetname "")
			)
			(fill
				(thermal_gap 0.5)
				(thermal_bridge_width 0.5)
				(island_removal_mode 0)
			)
			(polygon
				(pts
					(xy 429.474122 -44.800774) (xy 429.474122 -45.308774) (xy 429.855122 -45.308774) (xy 429.855122 -44.800774)
				)
			)
		)
		(zone
			(layer "F.Cu")
			(hatch none 0.5)
			(connect_pads
				(clearance 0)
			)
			(min_thickness 0.25)
			(keepout
				(tracks not_allowed)
				(vias allowed)
				(pads allowed)
				(copperpour not_allowed)
				(footprints allowed)
			)
			(placement
				(enabled no)
				(sheetname "")
			)
			(fill
				(thermal_gap 0.5)
				(thermal_bridge_width 0.5)
				(island_removal_mode 0)
			)
			(polygon
				(pts
					(xy 429.855122 -44.800774) (xy 429.855122 -45.308774) (xy 429.474122 -45.308774) (xy 429.474122 -44.800774)
				)
			)
		)
	)
	(footprint ""
		(layer "F.Cu")
		(at 475.7801 -141.6177 180)
		(property "Reference" "C1L17"
			(at 0 0 180)
			(layer "F.SilkS")
			(hide yes)
			(effects
				(font
					(size 1.27 1.27)
				)
			)
		)
		(property "Value" ""
			(at 0 0 180)
			(layer "F.Fab")
			(effects
				(font
					(size 1.27 1.27)
				)
			)
		)
		(duplicate_pad_numbers_are_jumpers no)
		(fp_poly
			(pts
				(xy 0.3048 -0.1016) (xy 0.3048 0.9906) (xy -0.3048 0.9906) (xy -0.3048 -0.1016)
			)
			(stroke
				(width 0)
				(type default)
			)
			(fill no)
			(layer "F.CrtYd")
		)
		(fp_line
			(start 0.3048 0.9906)
			(end 0.3048 -0.1016)
			(stroke
				(width 0.1)
				(type default)
			)
			(layer "F.Fab")
		)
		(fp_line
			(start 0.3048 -0.1016)
			(end -0.3048 -0.1016)
			(stroke
				(width 0.1)
				(type default)
			)
			(layer "F.Fab")
		)
		(fp_line
			(start -0.3048 0.9906)
			(end 0.3048 0.9906)
			(stroke
				(width 0.1)
				(type default)
			)
			(layer "F.Fab")
		)
		(fp_line
			(start -0.3048 -0.1016)
			(end -0.3048 0.9906)
			(stroke
				(width 0.1)
				(type default)
			)
			(layer "F.Fab")
		)
		(pad "1" smd rect
			(at 0 0 180)
			(size 0.508 0.508)
			(layers "F.Cu" "F.Mask" "F.Paste")
			(net "P3V3_STBY")
		)
		(pad "2" smd rect
			(at 0 0.889 180)
			(size 0.508 0.508)
			(layers "F.Cu" "F.Mask" "F.Paste")
			(net "GND")
		)
		(zone
			(layer "F.Cu")
			(hatch none 0.5)
			(connect_pads
				(clearance 0)
			)
			(min_thickness 0.25)
			(keepout
				(tracks not_allowed)
				(vias allowed)
				(pads allowed)
				(copperpour not_allowed)
				(footprints allowed)
			)
			(placement
				(enabled no)
				(sheetname "")
			)
			(fill
				(thermal_gap 0.5)
				(thermal_bridge_width 0.5)
				(island_removal_mode 0)
			)
			(polygon
				(pts
					(xy 476.0341 -142.2527) (xy 475.5261 -142.2527) (xy 475.5261 -141.8717) (xy 476.0341 -141.8717)
				)
			)
		)
		(zone
			(layer "F.Cu")
			(hatch none 0.5)
			(connect_pads
				(clearance 0)
			)
			(min_thickness 0.25)
			(keepout
				(tracks allowed)
				(vias not_allowed)
				(pads allowed)
				(copperpour not_allowed)
				(footprints allowed)
			)
			(placement
				(enabled no)
				(sheetname "")
			)
			(fill
				(thermal_gap 0.5)
				(thermal_bridge_width 0.5)
				(island_removal_mode 0)
			)
			(polygon
				(pts
					(xy 476.0341 -141.8717) (xy 475.5261 -141.8717) (xy 475.5261 -142.2527) (xy 476.0341 -142.2527)
				)
			)
		)
	)
)
